# T6G (Grand Teton) — schematic parts with pin connectivity, parts 2611–2611 of 8303; source: Cadence DE-HDL packaged netlist (pstxprt.dat, pstxnet.dat, pstchip.dat)

J32  SCONN288_DDR506112002KQ  IO  pkg DDR288S_1-1VXC  page 102
  1  VIN_BULK0  POWER  = P12V_MEM_CPU1
  2  RFU0  TRI  = NC
  3  VIN_MGMT  POWER  = P3V3_AUX
  4  HSCL  IN  = I3C_SPD_DDRE_CPU1_SCL
  5  HSDA  BI  = I3C_SPD_DDRE_CPU1_SDA
  6  VSS0  POWER  = GND
  7  DQ0_A  BI  = M_E_CPU1_SA_DQ<0>
  8  VSS1  POWER  = GND
  9  DQ1_A  BI  = M_E_CPU1_SA_DQ<1>
  10  VSS2  POWER  = GND
  11  DQS0_A_T  BI  = M_E_CPU1_SA_DQS_DP<0>
  12  DQS0_A_C  BI  = M_E_CPU1_SA_DQS_DN<0>
  13  VSS3  POWER  = GND
  14  DQ4_A  BI  = M_E_CPU1_SA_DQ<4>
  15  VSS4  POWER  = GND
  16  DQ5_A  BI  = M_E_CPU1_SA_DQ<5>
  17  VSS5  POWER  = GND
  18  DQ8_A  BI  = M_E_CPU1_SA_DQ<8>
  19  VSS6  POWER  = GND
  20  DQ9_A  BI  = M_E_CPU1_SA_DQ<9>
  21  VSS7  POWER  = GND
  22  DQS1_A_T  BI  = M_E_CPU1_SA_DQS_DP<1>
  23  DQS1_A_C  BI  = M_E_CPU1_SA_DQS_DN<1>
  24  VSS8  POWER  = GND
  25  DQ12_A  BI  = M_E_CPU1_SA_DQ<12>
  26  VSS9  POWER  = GND
  27  DQ13_A  BI  = M_E_CPU1_SA_DQ<13>
  28  VSS10  POWER  = GND
  29  DQ16_A  BI  = M_E_CPU1_SA_DQ<16>
  30  VSS11  POWER  = GND
  31  DQ17_A  BI  = M_E_CPU1_SA_DQ<17>
  32  VSS12  POWER  = GND
  33  DQS2_A_T  BI  = M_E_CPU1_SA_DQS_DP<2>
  34  DQS2_A_C  BI  = M_E_CPU1_SA_DQS_DN<2>
  35  VSS13  POWER  = GND
  36  DQ20_A  BI  = M_E_CPU1_SA_DQ<20>
  37  VSS14  POWER  = GND
  38  DQ21_A  BI  = M_E_CPU1_SA_DQ<21>
  39  VSS15  POWER  = GND
  40  DQ24_A  BI  = M_E_CPU1_SA_DQ<24>
  41  VSS16  POWER  = GND
  42  DQ25_A  BI  = M_E_CPU1_SA_DQ<25>
  43  VSS17  POWER  = GND
  44  DQS3_A_T  BI  = M_E_CPU1_SA_DQS_DP<3>
  45  DQS3_A_C  BI  = M_E_CPU1_SA_DQS_DN<3>
  46  VSS18  POWER  = GND
  47  DQ28_A  BI  = M_E_CPU1_SA_DQ<28>
  48  VSS19  POWER  = GND
  49  DQ29_A  BI  = M_E_CPU1_SA_DQ<29>
  50  VSS20  POWER  = GND
  51  CB0_A  BI  = M_E_CPU1_SA_CB<0>
  52  VSS21  POWER  = GND
  53  CB1_A  BI  = M_E_CPU1_SA_CB<1>
  54  VSS22  POWER  = GND
  55  DQS4_A_T  BI  = M_E_CPU1_SA_DQS_DP<4>
  56  DQS4_A_C  BI  = M_E_CPU1_SA_DQS_DN<4>
  57  VSS23  POWER  = GND
  58  CB4_A  BI  = M_E_CPU1_SA_CB<4>
  59  VSS24  POWER  = GND
  60  CB5_A  BI  = M_E_CPU1_SA_CB<5>
  61  VSS25  POWER  = GND
  62  ALERT_N  OUT  = M_E_CPU1_ALERT_N
  63  VSS26  POWER  = GND
  64  CS0_A_N  IN  = M_E_CPU1_SA_CS_N<0>
  65  VSS27  POWER  = GND
  66  CA0_A  IN  = M_E_CPU1_SA_CA<0>
  67  VSS28  POWER  = GND
  68  CA2_A  IN  = M_E_CPU1_SA_CA<2>
  69  VSS29  POWER  = GND
  70  CA4_A  IN  = M_E_CPU1_SA_CA<4>
  71  VSS30  POWER  = GND
  72  CA6_A  IN  = M_E_CPU1_SA_CA<6>
  73  VSS31  POWER  = GND
  74  PAR_A  IN  = M_E_CPU1_SA_PAR
  75  VSS32  POWER  = GND
  76  CA0_B  IN  = M_E_CPU1_SB_CA<0>
  77  VSS33  POWER  = GND
  78  CA2_B  IN  = M_E_CPU1_SB_CA<2>
  79  VSS34  POWER  = GND
  80  CA4_B  IN  = M_E_CPU1_SB_CA<4>
  81  VSS35  POWER  = GND
  82  CA6_B  IN  = M_E_CPU1_SB_CA<6>
  83  VSS36  POWER  = GND
  84  CS0_B_N  IN  = M_E_CPU1_SB_CS_N<0>
  85  VSS37  POWER  = GND
  86  \lbd||rsp_a_n\  OUT  = M_E_CPU1_SA_RSP<0>
  87  \lbs||rsp_b_n\  OUT  = M_E_CPU1_SB_RSP<0>
  88  VSS38  POWER  = GND
  89  CB4_B  BI  = M_E_CPU1_SB_CB<4>
  90  VSS39  POWER  = GND
  91  CB5_B  BI  = M_E_CPU1_SB_CB<5>
  92  VSS40  POWER  = GND
  93  \dqs9_b_t||tdqs9_b_t||dbi4_b_n\  BI  = M_E_CPU1_SB_DQS_DP<9>
  94  \dqs9_b_c||tdqs9_b_c\  BI  = M_E_CPU1_SB_DQS_DN<9>
  95  VSS41  POWER  = GND
  96  CB0_B  BI  = M_E_CPU1_SB_CB<0>
  97  VSS42  POWER  = GND
  98  CB1_B  BI  = M_E_CPU1_SB_CB<1>
  99  VSS43  POWER  = GND
  100  DQ0_B  BI  = M_E_CPU1_SB_DQ<0>
  101  VSS44  POWER  = GND
  102  DQ1_B  BI  = M_E_CPU1_SB_DQ<1>
  103  VSS45  POWER  = GND
  104  DQS0_B_T  BI  = M_E_CPU1_SB_DQS_DP<0>
  105  DQS0_B_C  BI  = M_E_CPU1_SB_DQS_DN<0>
  106  VSS46  POWER  = GND
  107  DQ4_B  BI  = M_E_CPU1_SB_DQ<4>
  108  VSS47  POWER  = GND
  109  DQ5_B  BI  = M_E_CPU1_SB_DQ<5>
  110  VSS48  POWER  = GND
  111  DQ8_B  BI  = M_E_CPU1_SB_DQ<8>
  112  VSS49  POWER  = GND
  113  DQ9_B  BI  = M_E_CPU1_SB_DQ<9>
  114  VSS50  POWER  = GND
  115  DQS1_B_T  BI  = M_E_CPU1_SB_DQS_DP<1>
  116  DQS1_B_C  BI  = M_E_CPU1_SB_DQS_DN<1>
  117  VSS51  POWER  = GND
  118  DQ12_B  BI  = M_E_CPU1_SB_DQ<12>
  119  VSS52  POWER  = GND
  120  DQ13_B  BI  = M_E_CPU1_SB_DQ<13>
  121  VSS53  POWER  = GND
  122  DQ16_B  BI  = M_E_CPU1_SB_DQ<16>
  123  VSS54  POWER  = GND
  124  DQ17_B  BI  = M_E_CPU1_SB_DQ<17>
  125  VSS55  POWER  = GND
  126  DQS2_B_T  BI  = M_E_CPU1_SB_DQS_DP<2>
  127  DQS2_B_C  BI  = M_E_CPU1_SB_DQS_DN<2>
  128  VSS56  POWER  = GND
  129  DQ20_B  BI  = M_E_CPU1_SB_DQ<20>
  130  VSS57  POWER  = GND
  131  DQ21_B  BI  = M_E_CPU1_SB_DQ<21>
  132  VSS58  POWER  = GND
  133  DQ24_B  BI  = M_E_CPU1_SB_DQ<24>
  134  VSS59  POWER  = GND
  135  DQ25_B  BI  = M_E_CPU1_SB_DQ<25>
  136  VSS60  POWER  = GND
  137  DQS3_B_T  BI  = M_E_CPU1_SB_DQS_DP<3>
  138  DQS3_B_C  BI  = M_E_CPU1_SB_DQS_DN<3>
  139  VSS61  POWER  = GND
  140  DQ28_B  BI  = M_E_CPU1_SB_DQ<28>
  141  VSS62  POWER  = GND
  142  DQ29_B  BI  = M_E_CPU1_SB_DQ<29>
  143  VSS63  POWER  = GND
  144  RFU1  TRI  = NC
  145  VIN_BULK1  POWER  = P12V_MEM_CPU1
  146  VIN_BULK2  POWER  = P12V_MEM_CPU1
  147  \pwr_good||fail_n\  BI  = PWRGD_CHE_CPU1_DIMM
  148  HAS  IN  = PD_CHE_CPU1_DIMM_SAA
  149  RFU2  TRI  = NC
  150  RFU3  TRI  = NC
  151  VSS64  POWER  = GND
  152  DQ2_A  BI  = M_E_CPU1_SA_DQ<2>
  153  VSS65  POWER  = GND
  154  DQ3_A  BI  = M_E_CPU1_SA_DQ<3>
  155  VSS66  POWER  = GND
  156  \dqs5_a_c||tdqs5_a_c||dqs5_a_t||tdqs5_a_t\  BI  = M_E_CPU1_SA_DQS_DN<5>
  157  \dqs5_a_t||tdqs5_a_t\  BI  = M_E_CPU1_SA_DQS_DP<5>
  158  VSS67  POWER  = GND
  159  DQ6_A  BI  = M_E_CPU1_SA_DQ<6>
  160  VSS68  POWER  = GND
  161  DQ7_A  BI  = M_E_CPU1_SA_DQ<7>
  162  VSS69  POWER  = GND
  163  DQ10_A  BI  = M_E_CPU1_SA_DQ<10>
  164  VSS70  POWER  = GND
  165  DQ11_A  BI  = M_E_CPU1_SA_DQ<11>
  166  VSS71  POWER  = GND
  167  \dqs6_a_c||tdqs6_a_c||dqs6_a_t||tdqs6_a_t\  BI  = M_E_CPU1_SA_DQS_DN<6>
  168  \dqs6_a_t||tdqs6_a_t\  BI  = M_E_CPU1_SA_DQS_DP<6>
  169  VSS72  POWER  = GND
  170  DQ14_A  BI  = M_E_CPU1_SA_DQ<14>
  171  VSS73  POWER  = GND
  172  DQ15_A  BI  = M_E_CPU1_SA_DQ<15>
  173  VSS74  POWER  = GND
  174  DQ18_A  BI  = M_E_CPU1_SA_DQ<18>
  175  VSS75  POWER  = GND
  176  DQ19_A  BI  = M_E_CPU1_SA_DQ<19>
  177  VSS76  POWER  = GND
  178  \dqs7_a_c||tdqs7_a_c\  BI  = M_E_CPU1_SA_DQS_DN<7>
  179  \dqs7_a_t||tdqs7_a_t\  BI  = M_E_CPU1_SA_DQS_DP<7>
  180  VSS77  POWER  = GND
  181  DQ22_A  BI  = M_E_CPU1_SA_DQ<22>
  182  VSS78  POWER  = GND
  183  DQ23_A  BI  = M_E_CPU1_SA_DQ<23>
  184  VSS79  POWER  = GND
  185  DQ26_A  BI  = M_E_CPU1_SA_DQ<26>
  186  VSS80  POWER  = GND
  187  DQ27_A  BI  = M_E_CPU1_SA_DQ<27>
  188  VSS81  POWER  = GND
  189  \dqs8_a_c||tdqs8_a_c\  BI  = M_E_CPU1_SA_DQS_DN<8>
  190  \dqs8_a_t||tdqs8_a_t\  BI  = M_E_CPU1_SA_DQS_DP<8>
  191  VSS82  POWER  = GND
  192  DQ30_A  BI  = M_E_CPU1_SA_DQ<30>
  193  VSS83  POWER  = GND
  194  DQ31_A  BI  = M_E_CPU1_SA_DQ<31>
  195  VSS84  POWER  = GND
  196  CB2_A  BI  = M_E_CPU1_SA_CB<2>
  197  VSS85  POWER  = GND
  198  CB3_A  BI  = M_E_CPU1_SA_CB<3>
  199  VSS86  POWER  = GND
  200  \dqs9_a_c||tdqs9_a_c\  BI  = M_E_CPU1_SA_DQS_DN<9>
  201  \dqs9_a_t||tdqs9_a_t\  BI  = M_E_CPU1_SA_DQS_DP<9>
  202  VSS87  POWER  = GND
  203  CB6_A  BI  = M_E_CPU1_SA_CB<6>
  204  VSS88  POWER  = GND
  205  CB7_A  BI  = M_E_CPU1_SA_CB<7>
  206  VSS89  POWER  = GND
  207  RESET_N  IN  = M_E_CPU1_RESET_N
  208  VSS90  POWER  = GND
  209  CS1_A_N  IN  = M_E_CPU1_SA_CS_N<1>
  210  VSS91  POWER  = GND
  211  CA1_A  IN  = M_E_CPU1_SA_CA<1>
  212  VSS92  POWER  = GND
  213  CA3_A  IN  = M_E_CPU1_SA_CA<3>
  214  VSS93  POWER  = GND
  215  CA5_A  IN  = M_E_CPU1_SA_CA<5>
  216  VSS94  POWER  = GND
  217  CK_T  IN  = M_E_CPU1_CLK_DP<0>
  218  CK_C  IN  = M_E_CPU1_CLK_DN<0>
  219  VSS95  POWER  = GND
  220  RFU4  TRI  = NC
  221  CA1_B  IN  = M_E_CPU1_SB_CA<1>
  222  VSS96  POWER  = GND
  223  CA3_B  IN  = M_E_CPU1_SB_CA<3>
  224  VSS97  POWER  = GND
  225  CA5_B  IN  = M_E_CPU1_SB_CA<5>
  226  VSS98  POWER  = GND
  227  PAR_B  IN  = M_E_CPU1_SB_PAR
  228  VSS99  POWER  = GND
  229  CS1_B_N  IN  = M_E_CPU1_SB_CS_N<1>
  230  VSS100  POWER  = GND
  231  RFU5  TRI  = NC
  232  RFU6  TRI  = NC
  233  VSS101  POWER  = GND
  234  CB6_B  BI  = M_E_CPU1_SB_CB<6>
  235  VSS102  POWER  = GND
  236  CB7_B  BI  = M_E_CPU1_SB_CB<7>
  237  VSS103  POWER  = GND
  238  DQS4_B_C  BI  = M_E_CPU1_SB_DQS_DN<4>
  239  DQS4_B_T  BI  = M_E_CPU1_SB_DQS_DP<4>
  240  VSS104  POWER  = GND
  241  CB2_B  BI  = M_E_CPU1_SB_CB<2>
  242  VSS105  POWER  = GND
  243  CB3_B  BI  = M_E_CPU1_SB_CB<3>
  244  VSS106  POWER  = GND
  245  DQ2_B  BI  = M_E_CPU1_SB_DQ<2>
  246  VSS107  POWER  = GND
  247  DQ3_B  BI  = M_E_CPU1_SB_DQ<3>
  248  VSS108  POWER  = GND
  249  \dqs5_b_c||tdqs5_b_c\  BI  = M_E_CPU1_SB_DQS_DN<5>
  250  \dqs5_b_t||tdqs5_b_t\  BI  = M_E_CPU1_SB_DQS_DP<5>
  251  VSS109  POWER  = GND
  252  DQ6_B  BI  = M_E_CPU1_SB_DQ<6>
  253  VSS110  POWER  = GND
  254  DQ7_B  BI  = M_E_CPU1_SB_DQ<7>
  255  VSS111  POWER  = GND
  256  DQ10_B  BI  = M_E_CPU1_SB_DQ<10>
  257  VSS112  POWER  = GND
  258  DQ11_B  BI  = M_E_CPU1_SB_DQ<11>
  259  VSS113  POWER  = GND
  260  \dqs6_b_c||tdqs6_b_c\  BI  = M_E_CPU1_SB_DQS_DN<6>
  261  \dqs6_b_t||tdqs6_b_t\  BI  = M_E_CPU1_SB_DQS_DP<6>
  262  VSS114  POWER  = GND
  263  DQ14_B  BI  = M_E_CPU1_SB_DQ<14>
  264  VSS115  POWER  = GND
  265  DQ15_B  BI  = M_E_CPU1_SB_DQ<15>
  266  VSS116  POWER  = GND
  267  DQ18_B  BI  = M_E_CPU1_SB_DQ<18>
  268  VSS117  POWER  = GND
  269  DQ19_B  BI  = M_E_CPU1_SB_DQ<19>
  270  VSS118  POWER  = GND
  271  \dqs7_b_c||tdqs7_b_c\  BI  = M_E_CPU1_SB_DQS_DN<7>
  272  \dqs7_b_t||tdqs7_b_t\  BI  = M_E_CPU1_SB_DQS_DP<7>
  273  VSS119  POWER  = GND
  274  DQ22_B  BI  = M_E_CPU1_SB_DQ<22>
  275  VSS120  POWER  = GND
  276  DQ23_B  BI  = M_E_CPU1_SB_DQ<23>
  277  VSS121  POWER  = GND
  278  DQ26_B  BI  = M_E_CPU1_SB_DQ<26>
  279  VSS122  POWER  = GND
  280  DQ27_B  BI  = M_E_CPU1_SB_DQ<27>
  281  VSS123  POWER  = GND
  282  \dqs8_b_c||tdqs8_b_c\  BI  = M_E_CPU1_SB_DQS_DN<8>
  283  \dqs8_b_t||tdqs8_b_t\  BI  = M_E_CPU1_SB_DQS_DP<8>
  284  VSS124  POWER  = GND
  285  DQ30_B  BI  = M_E_CPU1_SB_DQ<30>
  286  VSS125  POWER  = GND
  287  DQ31_B  BI  = M_E_CPU1_SB_DQ<31>
  288  VSS126  POWER  = GND
  G1  G1  POWER  = GND
  G2  G2  POWER  = GND
  G3  G3  POWER  = GND
